(kicad_pcb
	(version 20260206)
	(generator "pcbnew")
	(generator_version "10.0")
	(general
		(thickness 1.6)
		(legacy_teardrops no)
	)
	(paper "A4")
	(title_block
		(title "01162023_DA0F0TEBIF0_F0T_Expander_BD_F_brd_V02_OCP.brd")
		(comment 1 "Grand Teton / footprints 1382-1388 of 9728")
	)
	(layers
		(0 "F.Cu" signal "TOP")
		(4 "In1.Cu" signal "GND")
		(6 "In2.Cu" signal "VCC")
		(8 "In3.Cu" signal "VCC1")
		(10 "In4.Cu" signal "GND1")
		(12 "In5.Cu" signal "IN1")
		(14 "In6.Cu" signal "GND2")
		(16 "In7.Cu" signal "IN2")
		(18 "In8.Cu" signal "GND3")
		(20 "In9.Cu" signal "IN3")
		(22 "In10.Cu" signal "GND4")
		(24 "In11.Cu" signal "IN4")
		(26 "In12.Cu" signal "GND5")
		(28 "In13.Cu" signal "IN5")
		(30 "In14.Cu" signal "GND6")
		(32 "In15.Cu" signal "IN6")
		(34 "In16.Cu" signal "GND7")
		(2 "B.Cu" signal "BOTTOM")
		(9 "F.Adhes" user "F.Adhesive")
		(11 "B.Adhes" user "B.Adhesive")
		(13 "F.Paste" user "Package Geometry/Pastemask Top")
		(15 "B.Paste" user "Package Geometry/Pastemask Bottom")
		(5 "F.SilkS" user "Ref Des/Silkscreen Top")
		(7 "B.SilkS" user "Ref Des/Silkscreen Bottom")
		(1 "F.Mask" user "Board Geometry/Soldermask Top")
		(3 "B.Mask" user "Board Geometry/Soldermask Bottom")
		(17 "Dwgs.User" user "User.Drawings")
		(19 "Cmts.User" user "User.Comments")
		(21 "Eco1.User" user "User.Eco1")
		(23 "Eco2.User" user "User.Eco2")
		(25 "Edge.Cuts" user "Board Geometry/Outline")
		(27 "Margin" user)
		(31 "F.CrtYd" user "Package Geometry/Place Bound Top")
		(29 "B.CrtYd" user "Package Geometry/Place Bound Bottom")
		(35 "F.Fab" user "Ref Des/Assembly Top")
		(33 "B.Fab" user "Ref Des/Assembly Bottom")
	)
	(footprint ""
		(layer "F.Cu")
		(at 45.7962 -47.20082 90)
		(property "Reference" "C205"
			(at 0 0 90)
			(layer "F.SilkS")
			(hide yes)
			(effects
				(font
					(size 1.27 1.27)
				)
			)
		)
		(property "Value" ""
			(at 0 0 90)
			(layer "F.Fab")
			(effects
				(font
					(size 1.27 1.27)
				)
			)
		)
		(duplicate_pad_numbers_are_jumpers no)
		(fp_line
			(start 0.7874 -0.4064)
			(end 0.7874 0.4064)
			(stroke
				(width 0.1524)
				(type default)
			)
			(layer "F.SilkS")
		)
		(fp_line
			(start -0.7874 -0.4064)
			(end 0.7874 -0.4064)
			(stroke
				(width 0.1524)
				(type default)
			)
			(layer "F.SilkS")
		)
		(fp_line
			(start 0.7874 0.4064)
			(end -0.7874 0.4064)
			(stroke
				(width 0.1524)
				(type default)
			)
			(layer "F.SilkS")
		)
		(fp_line
			(start -0.7874 0.4064)
			(end -0.7874 -0.4064)
			(stroke
				(width 0.1524)
				(type default)
			)
			(layer "F.SilkS")
		)
		(fp_line
			(start -0.12065 -0.305054)
			(end -0.12065 -0.2794)
			(stroke
				(width 0.1)
				(type default)
			)
			(layer "F.Fab")
		)
		(fp_line
			(start -0.67945 -0.305054)
			(end -0.12065 -0.305054)
			(stroke
				(width 0.1)
				(type default)
			)
			(layer "F.Fab")
		)
		(fp_line
			(start 0.67945 -0.3048)
			(end 0.67945 0.3048)
			(stroke
				(width 0.1)
				(type default)
			)
			(layer "F.Fab")
		)
		(fp_line
			(start 0.12065 -0.3048)
			(end 0.67945 -0.3048)
			(stroke
				(width 0.1)
				(type default)
			)
			(layer "F.Fab")
		)
		(fp_line
			(start 0.12065 -0.2794)
			(end 0.12065 -0.3048)
			(stroke
				(width 0.1)
				(type default)
			)
			(layer "F.Fab")
		)
		(fp_line
			(start -0.12065 -0.2794)
			(end 0.12065 -0.2794)
			(stroke
				(width 0.1)
				(type default)
			)
			(layer "F.Fab")
		)
		(fp_line
			(start 0.120396 0.2794)
			(end -0.12065 0.2794)
			(stroke
				(width 0.1)
				(type default)
			)
			(layer "F.Fab")
		)
		(fp_line
			(start -0.12065 0.2794)
			(end -0.12065 0.3048)
			(stroke
				(width 0.1)
				(type default)
			)
			(layer "F.Fab")
		)
		(fp_line
			(start 0.67945 0.3048)
			(end 0.120396 0.3048)
			(stroke
				(width 0.1)
				(type default)
			)
			(layer "F.Fab")
		)
		(fp_line
			(start 0.120396 0.3048)
			(end 0.120396 0.2794)
			(stroke
				(width 0.1)
				(type default)
			)
			(layer "F.Fab")
		)
		(fp_line
			(start -0.12065 0.3048)
			(end -0.67945 0.3048)
			(stroke
				(width 0.1)
				(type default)
			)
			(layer "F.Fab")
		)
		(fp_line
			(start -0.67945 0.3048)
			(end -0.67945 -0.305054)
			(stroke
				(width 0.1)
				(type default)
			)
			(layer "F.Fab")
		)
		(pad "1" smd circle
			(at -0.40005 0 90)
			(size 0 0)
			(layers "F.Cu" "F.Mask" "F.Paste")
			(net "P12V_SSD1_R")
		)
		(pad "2" smd circle
			(at 0.40005 0 90)
			(size 0 0)
			(layers "F.Cu" "F.Mask" "F.Paste")
			(net "GND")
		)
	)
	(footprint ""
		(layer "F.Cu")
		(at 8.633968 -156.288994 -90)
		(property "Reference" "PR6871"
			(at 0 0 270)
			(layer "F.SilkS")
			(hide yes)
			(effects
				(font
					(size 1.27 1.27)
				)
			)
		)
		(property "Value" ""
			(at 0 0 270)
			(layer "F.Fab")
			(effects
				(font
					(size 1.27 1.27)
				)
			)
		)
		(duplicate_pad_numbers_are_jumpers no)
		(fp_line
			(start -0.7874 0.4064)
			(end -0.7874 -0.4064)
			(stroke
				(width 0.1524)
				(type default)
			)
			(layer "F.SilkS")
		)
		(fp_line
			(start 0.7874 0.4064)
			(end -0.7874 0.4064)
			(stroke
				(width 0.1524)
				(type default)
			)
			(layer "F.SilkS")
		)
		(fp_line
			(start -0.7874 -0.4064)
			(end 0.7874 -0.4064)
			(stroke
				(width 0.1524)
				(type default)
			)
			(layer "F.SilkS")
		)
		(fp_line
			(start 0.7874 -0.4064)
			(end 0.7874 0.4064)
			(stroke
				(width 0.1524)
				(type default)
			)
			(layer "F.SilkS")
		)
		(fp_line
			(start -0.67945 0.3048)
			(end -0.67945 -0.305054)
			(stroke
				(width 0.1)
				(type default)
			)
			(layer "F.Fab")
		)
		(fp_line
			(start -0.12065 0.3048)
			(end -0.67945 0.3048)
			(stroke
				(width 0.1)
				(type default)
			)
			(layer "F.Fab")
		)
		(fp_line
			(start 0.120396 0.3048)
			(end 0.120396 0.2794)
			(stroke
				(width 0.1)
				(type default)
			)
			(layer "F.Fab")
		)
		(fp_line
			(start 0.67945 0.3048)
			(end 0.120396 0.3048)
			(stroke
				(width 0.1)
				(type default)
			)
			(layer "F.Fab")
		)
		(fp_line
			(start -0.12065 0.2794)
			(end -0.12065 0.3048)
			(stroke
				(width 0.1)
				(type default)
			)
			(layer "F.Fab")
		)
		(fp_line
			(start 0.120396 0.2794)
			(end -0.12065 0.2794)
			(stroke
				(width 0.1)
				(type default)
			)
			(layer "F.Fab")
		)
		(fp_line
			(start -0.12065 -0.2794)
			(end 0.12065 -0.2794)
			(stroke
				(width 0.1)
				(type default)
			)
			(layer "F.Fab")
		)
		(fp_line
			(start 0.12065 -0.2794)
			(end 0.12065 -0.3048)
			(stroke
				(width 0.1)
				(type default)
			)
			(layer "F.Fab")
		)
		(fp_line
			(start 0.12065 -0.3048)
			(end 0.67945 -0.3048)
			(stroke
				(width 0.1)
				(type default)
			)
			(layer "F.Fab")
		)
		(fp_line
			(start 0.67945 -0.3048)
			(end 0.67945 0.3048)
			(stroke
				(width 0.1)
				(type default)
			)
			(layer "F.Fab")
		)
		(fp_line
			(start -0.67945 -0.305054)
			(end -0.12065 -0.305054)
			(stroke
				(width 0.1)
				(type default)
			)
			(layer "F.Fab")
		)
		(fp_line
			(start -0.12065 -0.305054)
			(end -0.12065 -0.2794)
			(stroke
				(width 0.1)
				(type default)
			)
			(layer "F.Fab")
		)
		(pad "1" smd circle
			(at -0.40005 0 270)
			(size 0 0)
			(layers "F.Cu" "F.Mask" "F.Paste")
			(net "P12V_NIC0_CO_OV_FB")
		)
		(pad "2" smd circle
			(at 0.40005 0 270)
			(size 0 0)
			(layers "F.Cu" "F.Mask" "F.Paste")
			(net "GND")
		)
	)
	(footprint ""
		(layer "F.Cu")
		(at 450.415406 -42.853102 180)
		(property "Reference" "R5908"
			(at 0 0 180)
			(layer "F.SilkS")
			(hide yes)
			(effects
				(font
					(size 1.27 1.27)
				)
			)
		)
		(property "Value" ""
			(at 0 0 180)
			(layer "F.Fab")
			(effects
				(font
					(size 1.27 1.27)
				)
			)
		)
		(duplicate_pad_numbers_are_jumpers no)
		(fp_line
			(start 0.7874 0.4064)
			(end -0.7874 0.4064)
			(stroke
				(width 0.1524)
				(type default)
			)
			(layer "F.SilkS")
		)
		(fp_line
			(start 0.7874 -0.4064)
			(end 0.7874 0.4064)
			(stroke
				(width 0.1524)
				(type default)
			)
			(layer "F.SilkS")
		)
		(fp_line
			(start -0.7874 0.4064)
			(end -0.7874 -0.4064)
			(stroke
				(width 0.1524)
				(type default)
			)
			(layer "F.SilkS")
		)
		(fp_line
			(start -0.7874 -0.4064)
			(end 0.7874 -0.4064)
			(stroke
				(width 0.1524)
				(type default)
			)
			(layer "F.SilkS")
		)
		(fp_line
			(start 0.67945 0.3048)
			(end 0.120396 0.3048)
			(stroke
				(width 0.1)
				(type default)
			)
			(layer "F.Fab")
		)
		(fp_line
			(start 0.67945 -0.3048)
			(end 0.67945 0.3048)
			(stroke
				(width 0.1)
				(type default)
			)
			(layer "F.Fab")
		)
		(fp_line
			(start 0.12065 -0.2794)
			(end 0.12065 -0.3048)
			(stroke
				(width 0.1)
				(type default)
			)
			(layer "F.Fab")
		)
		(fp_line
			(start 0.12065 -0.3048)
			(end 0.67945 -0.3048)
			(stroke
				(width 0.1)
				(type default)
			)
			(layer "F.Fab")
		)
		(fp_line
			(start 0.120396 0.3048)
			(end 0.120396 0.2794)
			(stroke
				(width 0.1)
				(type default)
			)
			(layer "F.Fab")
		)
		(fp_line
			(start 0.120396 0.2794)
			(end -0.12065 0.2794)
			(stroke
				(width 0.1)
				(type default)
			)
			(layer "F.Fab")
		)
		(fp_line
			(start -0.12065 0.3048)
			(end -0.67945 0.3048)
			(stroke
				(width 0.1)
				(type default)
			)
			(layer "F.Fab")
		)
		(fp_line
			(start -0.12065 0.2794)
			(end -0.12065 0.3048)
			(stroke
				(width 0.1)
				(type default)
			)
			(layer "F.Fab")
		)
		(fp_line
			(start -0.12065 -0.2794)
			(end 0.12065 -0.2794)
			(stroke
				(width 0.1)
				(type default)
			)
			(layer "F.Fab")
		)
		(fp_line
			(start -0.12065 -0.305054)
			(end -0.12065 -0.2794)
			(stroke
				(width 0.1)
				(type default)
			)
			(layer "F.Fab")
		)
		(fp_line
			(start -0.67945 0.3048)
			(end -0.67945 -0.305054)
			(stroke
				(width 0.1)
				(type default)
			)
			(layer "F.Fab")
		)
		(fp_line
			(start -0.67945 -0.305054)
			(end -0.12065 -0.305054)
			(stroke
				(width 0.1)
				(type default)
			)
			(layer "F.Fab")
		)
		(pad "1" smd circle
			(at -0.40005 0 180)
			(size 0 0)
			(layers "F.Cu" "F.Mask" "F.Paste")
			(net "SSD15_ADC_A1")
		)
		(pad "2" smd circle
			(at 0.40005 0 180)
			(size 0 0)
			(layers "F.Cu" "F.Mask" "F.Paste")
			(net "SMB_SSD15_ADC_SCL")
		)
	)
	(footprint ""
		(layer "F.Cu")
		(at 248.094754 -274.487386)
		(property "Reference" "R794"
			(at 0 0 0)
			(layer "F.SilkS")
			(hide yes)
			(effects
				(font
					(size 1.27 1.27)
				)
			)
		)
		(property "Value" ""
			(at 0 0 0)
			(layer "F.Fab")
			(effects
				(font
					(size 1.27 1.27)
				)
			)
		)
		(duplicate_pad_numbers_are_jumpers no)
		(fp_line
			(start -0.7874 -0.4064)
			(end 0.7874 -0.4064)
			(stroke
				(width 0.1524)
				(type default)
			)
			(layer "F.SilkS")
		)
		(fp_line
			(start -0.7874 0.4064)
			(end -0.7874 -0.4064)
			(stroke
				(width 0.1524)
				(type default)
			)
			(layer "F.SilkS")
		)
		(fp_line
			(start 0.7874 -0.4064)
			(end 0.7874 0.4064)
			(stroke
				(width 0.1524)
				(type default)
			)
			(layer "F.SilkS")
		)
		(fp_line
			(start 0.7874 0.4064)
			(end -0.7874 0.4064)
			(stroke
				(width 0.1524)
				(type default)
			)
			(layer "F.SilkS")
		)
		(fp_line
			(start -0.67945 -0.305054)
			(end -0.12065 -0.305054)
			(stroke
				(width 0.1)
				(type default)
			)
			(layer "F.Fab")
		)
		(fp_line
			(start -0.67945 0.3048)
			(end -0.67945 -0.305054)
			(stroke
				(width 0.1)
				(type default)
			)
			(layer "F.Fab")
		)
		(fp_line
			(start -0.12065 -0.305054)
			(end -0.12065 -0.2794)
			(stroke
				(width 0.1)
				(type default)
			)
			(layer "F.Fab")
		)
		(fp_line
			(start -0.12065 -0.2794)
			(end 0.12065 -0.2794)
			(stroke
				(width 0.1)
				(type default)
			)
			(layer "F.Fab")
		)
		(fp_line
			(start -0.12065 0.2794)
			(end -0.12065 0.3048)
			(stroke
				(width 0.1)
				(type default)
			)
			(layer "F.Fab")
		)
		(fp_line
			(start -0.12065 0.3048)
			(end -0.67945 0.3048)
			(stroke
				(width 0.1)
				(type default)
			)
			(layer "F.Fab")
		)
		(fp_line
			(start 0.120396 0.2794)
			(end -0.12065 0.2794)
			(stroke
				(width 0.1)
				(type default)
			)
			(layer "F.Fab")
		)
		(fp_line
			(start 0.120396 0.3048)
			(end 0.120396 0.2794)
			(stroke
				(width 0.1)
				(type default)
			)
			(layer "F.Fab")
		)
		(fp_line
			(start 0.12065 -0.3048)
			(end 0.67945 -0.3048)
			(stroke
				(width 0.1)
				(type default)
			)
			(layer "F.Fab")
		)
		(fp_line
			(start 0.12065 -0.2794)
			(end 0.12065 -0.3048)
			(stroke
				(width 0.1)
				(type default)
			)
			(layer "F.Fab")
		)
		(fp_line
			(start 0.67945 -0.3048)
			(end 0.67945 0.3048)
			(stroke
				(width 0.1)
				(type default)
			)
			(layer "F.Fab")
		)
		(fp_line
			(start 0.67945 0.3048)
			(end 0.120396 0.3048)
			(stroke
				(width 0.1)
				(type default)
			)
			(layer "F.Fab")
		)
		(pad "1" smd circle
			(at -0.40005 0)
			(size 0 0)
			(layers "F.Cu" "F.Mask" "F.Paste")
			(net "PEX2_P1V25_ADC_A1")
		)
		(pad "2" smd circle
			(at 0.40005 0)
			(size 0 0)
			(layers "F.Cu" "F.Mask" "F.Paste")
			(net "GND")
		)
	)
	(footprint ""
		(layer "F.Cu")
		(at 137.390124 -72.766682 90)
		(property "Reference" "PR7064"
			(at 0 0 90)
			(layer "F.SilkS")
			(hide yes)
			(effects
				(font
					(size 1.27 1.27)
				)
			)
		)
		(property "Value" ""
			(at 0 0 90)
			(layer "F.Fab")
			(effects
				(font
					(size 1.27 1.27)
				)
			)
		)
		(duplicate_pad_numbers_are_jumpers no)
		(fp_line
			(start 0.7874 -0.4064)
			(end 0.7874 0.4064)
			(stroke
				(width 0.1524)
				(type default)
			)
			(layer "F.SilkS")
		)
		(fp_line
			(start -0.7874 -0.4064)
			(end 0.7874 -0.4064)
			(stroke
				(width 0.1524)
				(type default)
			)
			(layer "F.SilkS")
		)
		(fp_line
			(start 0.7874 0.4064)
			(end -0.7874 0.4064)
			(stroke
				(width 0.1524)
				(type default)
			)
			(layer "F.SilkS")
		)
		(fp_line
			(start -0.7874 0.4064)
			(end -0.7874 -0.4064)
			(stroke
				(width 0.1524)
				(type default)
			)
			(layer "F.SilkS")
		)
		(fp_line
			(start -0.12065 -0.305054)
			(end -0.12065 -0.2794)
			(stroke
				(width 0.1)
				(type default)
			)
			(layer "F.Fab")
		)
		(fp_line
			(start -0.67945 -0.305054)
			(end -0.12065 -0.305054)
			(stroke
				(width 0.1)
				(type default)
			)
			(layer "F.Fab")
		)
		(fp_line
			(start 0.67945 -0.3048)
			(end 0.67945 0.3048)
			(stroke
				(width 0.1)
				(type default)
			)
			(layer "F.Fab")
		)
		(fp_line
			(start 0.12065 -0.3048)
			(end 0.67945 -0.3048)
			(stroke
				(width 0.1)
				(type default)
			)
			(layer "F.Fab")
		)
		(fp_line
			(start 0.12065 -0.2794)
			(end 0.12065 -0.3048)
			(stroke
				(width 0.1)
				(type default)
			)
			(layer "F.Fab")
		)
		(fp_line
			(start -0.12065 -0.2794)
			(end 0.12065 -0.2794)
			(stroke
				(width 0.1)
				(type default)
			)
			(layer "F.Fab")
		)
		(fp_line
			(start 0.120396 0.2794)
			(end -0.12065 0.2794)
			(stroke
				(width 0.1)
				(type default)
			)
			(layer "F.Fab")
		)
		(fp_line
			(start -0.12065 0.2794)
			(end -0.12065 0.3048)
			(stroke
				(width 0.1)
				(type default)
			)
			(layer "F.Fab")
		)
		(fp_line
			(start 0.67945 0.3048)
			(end 0.120396 0.3048)
			(stroke
				(width 0.1)
				(type default)
			)
			(layer "F.Fab")
		)
		(fp_line
			(start 0.120396 0.3048)
			(end 0.120396 0.2794)
			(stroke
				(width 0.1)
				(type default)
			)
			(layer "F.Fab")
		)
		(fp_line
			(start -0.12065 0.3048)
			(end -0.67945 0.3048)
			(stroke
				(width 0.1)
				(type default)
			)
			(layer "F.Fab")
		)
		(fp_line
			(start -0.67945 0.3048)
			(end -0.67945 -0.305054)
			(stroke
				(width 0.1)
				(type default)
			)
			(layer "F.Fab")
		)
		(pad "1" smd circle
			(at -0.40005 0 90)
			(size 0 0)
			(layers "F.Cu" "F.Mask" "F.Paste")
			(net "P12V_SSD4_CO_ILIMIT")
		)
		(pad "2" smd circle
			(at 0.40005 0 90)
			(size 0 0)
			(layers "F.Cu" "F.Mask" "F.Paste")
			(net "GND")
		)
	)
	(footprint ""
		(layer "F.Cu")
		(at 29.548328 -356.244906 90)
		(property "Reference" "C182"
			(at 0 0 90)
			(layer "F.SilkS")
			(hide yes)
			(effects
				(font
					(size 1.27 1.27)
				)
			)
		)
		(property "Value" ""
			(at 0 0 90)
			(layer "F.Fab")
			(effects
				(font
					(size 1.27 1.27)
				)
			)
		)
		(duplicate_pad_numbers_are_jumpers no)
		(fp_line
			(start 0.299974 -0.150114)
			(end 0.299974 0.150114)
			(stroke
				(width 0.1)
				(type default)
			)
			(layer "F.Fab")
		)
		(fp_line
			(start -0.299974 -0.150114)
			(end 0.299974 -0.150114)
			(stroke
				(width 0.1)
				(type default)
			)
			(layer "F.Fab")
		)
		(fp_line
			(start 0.299974 0.150114)
			(end -0.299974 0.150114)
			(stroke
				(width 0.1)
				(type default)
			)
			(layer "F.Fab")
		)
		(fp_line
			(start -0.299974 0.150114)
			(end -0.299974 -0.150114)
			(stroke
				(width 0.1)
				(type default)
			)
			(layer "F.Fab")
		)
		(pad "1" smd rect
			(at -0.2667 0 90)
			(size 0.3048 0.381)
			(layers "F.Cu" "F.Mask" "F.Paste")
			(net "P5E_PEX0_STN7_TX_DN<117>")
		)
		(pad "2" smd rect
			(at 0.2667 0 90)
			(size 0.3048 0.381)
			(layers "F.Cu" "F.Mask" "F.Paste")
			(net "P5E_PEX0_STN7_TX_C_DN<117>")
		)
	)
	(footprint ""
		(layer "F.Cu")
		(at 85.757766 -299.04055 -90)
		(property "Reference" "C4185"
			(at 0 0 270)
			(layer "F.SilkS")
			(hide yes)
			(effects
				(font
					(size 1.27 1.27)
				)
			)
		)
		(property "Value" ""
			(at 0 0 270)
			(layer "F.Fab")
			(effects
				(font
					(size 1.27 1.27)
				)
			)
		)
		(duplicate_pad_numbers_are_jumpers no)
		(fp_line
			(start -0.7874 0.4064)
			(end -0.7874 -0.4064)
			(stroke
				(width 0.1524)
				(type default)
			)
			(layer "F.SilkS")
		)
		(fp_line
			(start 0.7874 0.4064)
			(end -0.7874 0.4064)
			(stroke
				(width 0.1524)
				(type default)
			)
			(layer "F.SilkS")
		)
		(fp_line
			(start -0.7874 -0.4064)
			(end 0.7874 -0.4064)
			(stroke
				(width 0.1524)
				(type default)
			)
			(layer "F.SilkS")
		)
		(fp_line
			(start 0.7874 -0.4064)
			(end 0.7874 0.4064)
			(stroke
				(width 0.1524)
				(type default)
			)
			(layer "F.SilkS")
		)
		(fp_line
			(start -0.67945 0.3048)
			(end -0.67945 -0.305054)
			(stroke
				(width 0.1)
				(type default)
			)
			(layer "F.Fab")
		)
		(fp_line
			(start -0.12065 0.3048)
			(end -0.67945 0.3048)
			(stroke
				(width 0.1)
				(type default)
			)
			(layer "F.Fab")
		)
		(fp_line
			(start 0.120396 0.3048)
			(end 0.120396 0.2794)
			(stroke
				(width 0.1)
				(type default)
			)
			(layer "F.Fab")
		)
		(fp_line
			(start 0.67945 0.3048)
			(end 0.120396 0.3048)
			(stroke
				(width 0.1)
				(type default)
			)
			(layer "F.Fab")
		)
		(fp_line
			(start -0.12065 0.2794)
			(end -0.12065 0.3048)
			(stroke
				(width 0.1)
				(type default)
			)
			(layer "F.Fab")
		)
		(fp_line
			(start 0.120396 0.2794)
			(end -0.12065 0.2794)
			(stroke
				(width 0.1)
				(type default)
			)
			(layer "F.Fab")
		)
		(fp_line
			(start -0.12065 -0.2794)
			(end 0.12065 -0.2794)
			(stroke
				(width 0.1)
				(type default)
			)
			(layer "F.Fab")
		)
		(fp_line
			(start 0.12065 -0.2794)
			(end 0.12065 -0.3048)
			(stroke
				(width 0.1)
				(type default)
			)
			(layer "F.Fab")
		)
		(fp_line
			(start 0.12065 -0.3048)
			(end 0.67945 -0.3048)
			(stroke
				(width 0.1)
				(type default)
			)
			(layer "F.Fab")
		)
		(fp_line
			(start 0.67945 -0.3048)
			(end 0.67945 0.3048)
			(stroke
				(width 0.1)
				(type default)
			)
			(layer "F.Fab")
		)
		(fp_line
			(start -0.67945 -0.305054)
			(end -0.12065 -0.305054)
			(stroke
				(width 0.1)
				(type default)
			)
			(layer "F.Fab")
		)
		(fp_line
			(start -0.12065 -0.305054)
			(end -0.12065 -0.2794)
			(stroke
				(width 0.1)
				(type default)
			)
			(layer "F.Fab")
		)
		(pad "1" smd circle
			(at -0.40005 0 270)
			(size 0 0)
			(layers "F.Cu" "F.Mask" "F.Paste")
			(net "GND")
		)
		(pad "2" smd circle
			(at 0.40005 0 270)
			(size 0 0)
			(layers "F.Cu" "F.Mask" "F.Paste")
			(net "P1V8_PEX")
		)
	)
)
